(kicad_pcb
	(version 20241229)
	(generator "pcbnew")
	(generator_version "9.0")
	(general
		(thickness 1.711)
		(legacy_teardrops no)
	)
	(paper "A4")
	(title_block
		(title "Antmicro Baseboard for Jetson AGX Thor")
		(date "2026-02-18")
		(rev "1.1.0")
		(company "Antmicro Ltd")
		(comment 1 "www.antmicro.com")
		(comment 9 "footprints 1164-1168 of 1170")
	)
	(layers
		(0 "F.Cu" signal)
		(4 "In1.Cu" signal)
		(6 "In2.Cu" signal)
		(8 "In3.Cu" signal)
		(10 "In4.Cu" jumper)
		(12 "In5.Cu" signal)
		(14 "In6.Cu" signal)
		(16 "In7.Cu" signal)
		(18 "In8.Cu" signal)
		(2 "B.Cu" signal)
		(9 "F.Adhes" user "F.Adhesive")
		(11 "B.Adhes" user "B.Adhesive")
		(13 "F.Paste" user)
		(15 "B.Paste" user)
		(5 "F.SilkS" user "F.Silkscreen")
		(7 "B.SilkS" user "B.Silkscreen")
		(1 "F.Mask" user)
		(3 "B.Mask" user)
		(17 "Dwgs.User" user "User.Drawings")
		(19 "Cmts.User" user "User.Comments")
		(21 "Eco1.User" user "User.Eco1")
		(23 "Eco2.User" user "User.Eco2")
		(25 "Edge.Cuts" user)
		(27 "Margin" user)
		(31 "F.CrtYd" user "F.Courtyard")
		(29 "B.CrtYd" user "B.Courtyard")
		(35 "F.Fab" user)
		(33 "B.Fab" user)
	)
	(footprint "antmicro-footprints:TP_SMD_0.75mm"
		(layer "B.Cu")
		(at 125.4 69.4 90)
		(property "Reference" "TP57"
			(at 0.5 -0.3 90)
			(layer "B.SilkS")
			(effects
				(font
					(size 0.7 0.7)
					(thickness 0.15)
				)
				(justify right top mirror)
			)
		)
		(property "Value" "TP_0.75mm_SMD"
			(at 0 -1.2 90)
			(layer "B.Fab")
			(effects
				(font
					(size 0.7 0.7)
					(thickness 0.15)
				)
				(justify right top mirror)
			)
		)
		(property "Description" "SMT test point"
			(at 0 0 90)
			(layer "B.Fab")
			(hide yes)
			(effects
				(font
					(size 1.27 1.27)
					(thickness 0.15)
				)
				(justify mirror)
			)
		)
		(property "MPN" ""
			(at 0 0 270)
			(unlocked yes)
			(layer "B.Fab")
			(hide yes)
			(effects
				(font
					(size 1 1)
					(thickness 0.15)
				)
				(justify mirror)
			)
		)
		(property "Manufacturer" ""
			(at 0 0 270)
			(unlocked yes)
			(layer "B.Fab")
			(hide yes)
			(effects
				(font
					(size 1 1)
					(thickness 0.15)
				)
				(justify mirror)
			)
		)
		(property "Author" "Antmicro"
			(at 0 0 270)
			(unlocked yes)
			(layer "B.Fab")
			(hide yes)
			(effects
				(font
					(size 1 1)
					(thickness 0.15)
				)
				(justify mirror)
			)
		)
		(property "License" "Apache-2.0"
			(at 0 0 270)
			(unlocked yes)
			(layer "B.Fab")
			(hide yes)
			(effects
				(font
					(size 1 1)
					(thickness 0.15)
				)
				(justify mirror)
			)
		)
		(sheetname "/SoM_Power/")
		(sheetfile "som_power.kicad_sch")
		(attr exclude_from_pos_files exclude_from_bom)
		(fp_circle
			(center 0 0)
			(end 0.475 0)
			(stroke
				(width 0.05)
				(type default)
			)
			(fill no)
			(layer "B.CrtYd")
		)
		(fp_text user "Author: Antmicro"
			(at -0.4 -3.901 90)
			(layer "B.Fab")
			(effects
				(font
					(size 0.7 0.7)
					(thickness 0.15)
				)
				(justify right top mirror)
			)
		)
		(fp_text user "${REFERENCE}"
			(at -0.4 -2.7 90)
			(layer "B.Fab")
			(effects
				(font
					(size 0.7 0.7)
					(thickness 0.15)
				)
				(justify right top mirror)
			)
		)
		(fp_text user "License: Apache-2.0"
			(at -0.4 -5.101 90)
			(layer "B.Fab")
			(effects
				(font
					(size 0.7 0.7)
					(thickness 0.15)
				)
				(justify right top mirror)
			)
		)
		(pad "1" smd circle
			(at 0 0 90)
			(size 0.75 0.75)
			(layers "B.Cu" "B.Mask")
			(net 566 "Net-(J1A-VM_SLEEP_N)")
			(pinfunction "1")
			(pintype "passive")
		)
	)
	(footprint "antmicro-footprints:R_0402_1005Metric"
		(layer "B.Cu")
		(at 109.82 132.3 180)
		(descr "Resistor SMD 0402")
		(tags "resistor SMD 0402")
		(property "Reference" "R220"
			(at 3.82 0.3 180)
			(layer "B.SilkS")
			(effects
				(font
					(size 0.7 0.7)
					(thickness 0.15)
				)
				(justify right top mirror)
			)
		)
		(property "Value" "R_47k_0402"
			(at -1.011843 -1.772047 180)
			(layer "B.Fab")
			(effects
				(font
					(size 0.7 0.7)
					(thickness 0.15)
				)
				(justify right top mirror)
			)
		)
		(property "Datasheet" "https://www.bourns.com/docs/product-datasheets/cr.pdf"
			(at 0 0 180)
			(layer "B.Fab")
			(hide yes)
			(effects
				(font
					(size 1.27 1.27)
					(thickness 0.15)
				)
				(justify mirror)
			)
		)
		(property "Description" "SMD Chip Resistor, 47 kohm, ± 1%, 62.5 mW, 0402 [1005 Metric], Thick Film, General Purpose"
			(at 0 0 180)
			(layer "B.Fab")
			(hide yes)
			(effects
				(font
					(size 1.27 1.27)
					(thickness 0.15)
				)
				(justify mirror)
			)
		)
		(property "MPN" "CR0402-FX-4702GLF"
			(at 0 0 0)
			(unlocked yes)
			(layer "B.Fab")
			(hide yes)
			(effects
				(font
					(size 1 1)
					(thickness 0.15)
				)
				(justify mirror)
			)
		)
		(property "Manufacturer" "Bourns"
			(at 0 0 0)
			(unlocked yes)
			(layer "B.Fab")
			(hide yes)
			(effects
				(font
					(size 1 1)
					(thickness 0.15)
				)
				(justify mirror)
			)
		)
		(property "License" "Apache-2.0"
			(at 0 0 0)
			(unlocked yes)
			(layer "B.Fab")
			(hide yes)
			(effects
				(font
					(size 1 1)
					(thickness 0.15)
				)
				(justify mirror)
			)
		)
		(property "Author" "Antmicro"
			(at 0 0 0)
			(unlocked yes)
			(layer "B.Fab")
			(hide yes)
			(effects
				(font
					(size 1 1)
					(thickness 0.15)
				)
				(justify mirror)
			)
		)
		(property "Val" "47k"
			(at 0 0 0)
			(unlocked yes)
			(layer "B.Fab")
			(hide yes)
			(effects
				(font
					(size 1 1)
					(thickness 0.15)
				)
				(justify mirror)
			)
		)
		(property "Tolerance" "1%"
			(at 0 0 0)
			(unlocked yes)
			(layer "B.Fab")
			(hide yes)
			(effects
				(font
					(size 1 1)
					(thickness 0.15)
				)
				(justify mirror)
			)
		)
		(sheetname "/M.2/")
		(sheetfile "m2.kicad_sch")
		(attr smd)
		(fp_rect
			(start -0.925 0.47)
			(end 0.925 -0.47)
			(stroke
				(width 0.05)
				(type default)
			)
			(fill no)
			(layer "B.CrtYd")
		)
		(fp_rect
			(start -0.5 0.25)
			(end 0.5 -0.25)
			(stroke
				(width 0.15)
				(type solid)
			)
			(fill no)
			(layer "B.Fab")
		)
		(fp_text user "${REFERENCE}"
			(at -0.95 -3.168 180)
			(layer "B.Fab")
			(effects
				(font
					(size 0.7 0.7)
					(thickness 0.15)
				)
				(justify right top mirror)
			)
		)
		(fp_text user "Author: Antmicro"
			(at -0.95 -4.169 180)
			(layer "B.Fab")
			(effects
				(font
					(size 0.7 0.7)
					(thickness 0.15)
				)
				(justify right top mirror)
			)
		)
		(fp_text user "License: Apache-2.0"
			(at -0.95 -5.169 180)
			(layer "B.Fab")
			(effects
				(font
					(size 0.7 0.7)
					(thickness 0.15)
				)
				(justify right top mirror)
			)
		)
		(pad "1" smd roundrect
			(at -0.48 0 180)
			(size 0.59 0.64)
			(layers "B.Cu" "B.Mask" "B.Paste")
			(roundrect_rratio 0.25)
			(net 834 "/M.2/~{CLKREQ_E}")
			(pintype "passive")
		)
		(pad "2" smd roundrect
			(at 0.48 0 180)
			(size 0.59 0.64)
			(layers "B.Cu" "B.Mask" "B.Paste")
			(roundrect_rratio 0.25)
			(net 2 "+3V3")
			(pintype "passive")
		)
	)
	(footprint "antmicro-footprints:SOT-563"
		(layer "B.Cu")
		(at 217.04 111.24 90)
		(property "Reference" "Q26"
			(at -1.06 -2.04 90)
			(layer "B.SilkS")
			(effects
				(font
					(size 0.7 0.7)
					(thickness 0.15)
				)
				(justify right top mirror)
			)
		)
		(property "Value" "DMC2400UV-7"
			(at 0 -2 90)
			(layer "B.Fab")
			(effects
				(font
					(size 0.7 0.7)
					(thickness 0.15)
				)
				(justify right top mirror)
			)
		)
		(property "Datasheet" "https://www.mouser.com/datasheet/2/115/DIOD_S_A0010038249_1-2543538.pdf"
			(at 0 0 90)
			(layer "B.Fab")
			(hide yes)
			(effects
				(font
					(size 1.27 1.27)
					(thickness 0.15)
				)
				(justify mirror)
			)
		)
		(property "Description" "Dual MOSFET, Complementary N and P Channel, 20 V, 20 V, 1.03 A, 1.03 A, 0.3 ohm"
			(at 0 0 90)
			(layer "B.Fab")
			(hide yes)
			(effects
				(font
					(size 1.27 1.27)
					(thickness 0.15)
				)
				(justify mirror)
			)
		)
		(property "MPN" "DMC2400UV-7"
			(at 0 0 270)
			(unlocked yes)
			(layer "B.Fab")
			(hide yes)
			(effects
				(font
					(size 1 1)
					(thickness 0.15)
				)
				(justify mirror)
			)
		)
		(property "Manufacturer" "Diodes Incorporated"
			(at 0 0 270)
			(unlocked yes)
			(layer "B.Fab")
			(hide yes)
			(effects
				(font
					(size 1 1)
					(thickness 0.15)
				)
				(justify mirror)
			)
		)
		(property "Author" "Antmicro"
			(at 0 0 270)
			(unlocked yes)
			(layer "B.Fab")
			(hide yes)
			(effects
				(font
					(size 1 1)
					(thickness 0.15)
				)
				(justify mirror)
			)
		)
		(property "License" "Apache-2.0"
			(at 0 0 270)
			(unlocked yes)
			(layer "B.Fab")
			(hide yes)
			(effects
				(font
					(size 1 1)
					(thickness 0.15)
				)
				(justify mirror)
			)
		)
		(sheetname "/USB Hub/")
		(sheetfile "usb_hub.kicad_sch")
		(attr smd)
		(fp_line
			(start 0.776 -0.972)
			(end 0.526 -0.972)
			(stroke
				(width 0.15)
				(type solid)
			)
			(layer "B.SilkS")
		)
		(fp_line
			(start -0.778 -0.949)
			(end -0.424 -0.949)
			(stroke
				(width 0.15)
				(type solid)
			)
			(layer "B.SilkS")
		)
		(fp_line
			(start 0.776 -0.776)
			(end 0.776 -0.972)
			(stroke
				(width 0.15)
				(type solid)
			)
			(layer "B.SilkS")
		)
		(fp_line
			(start -0.778 -0.776)
			(end -0.778 -0.949)
			(stroke
				(width 0.15)
				(type solid)
			)
			(layer "B.SilkS")
		)
		(fp_line
			(start 0.776 0.974)
			(end 0.776 0.778)
			(stroke
				(width 0.15)
				(type solid)
			)
			(layer "B.SilkS")
		)
		(fp_line
			(start 0.776 0.974)
			(end 0.526 0.974)
			(stroke
				(width 0.15)
				(type solid)
			)
			(layer "B.SilkS")
		)
		(fp_line
			(start -0.499 0.974)
			(end -0.724 0.778)
			(stroke
				(width 0.15)
				(type solid)
			)
			(layer "B.SilkS")
		)
		(fp_circle
			(center -0.903 0.999)
			(end -0.952 0.95)
			(stroke
				(width 0.15)
				(type solid)
			)
			(fill yes)
			(layer "B.SilkS")
		)
		(fp_rect
			(start 1.19 1.12)
			(end -1.2 -1.1)
			(stroke
				(width 0.05)
				(type solid)
			)
			(fill no)
			(layer "B.CrtYd")
		)
		(fp_line
			(start 0.651 -0.847)
			(end -0.653 -0.847)
			(stroke
				(width 0.15)
				(type solid)
			)
			(layer "B.Fab")
		)
		(fp_line
			(start -0.653 0.678)
			(end -0.653 -0.847)
			(stroke
				(width 0.15)
				(type solid)
			)
			(layer "B.Fab")
		)
		(fp_line
			(start 0.651 0.849)
			(end 0.651 -0.847)
			(stroke
				(width 0.15)
				(type solid)
			)
			(layer "B.Fab")
		)
		(fp_line
			(start -0.453 0.849)
			(end -0.653 0.678)
			(stroke
				(width 0.15)
				(type solid)
			)
			(layer "B.Fab")
		)
		(fp_line
			(start -0.453 0.849)
			(end 0.651 0.849)
			(stroke
				(width 0.15)
				(type solid)
			)
			(layer "B.Fab")
		)
		(fp_text user "Author: Antmicro"
			(at -1.299 -6.124 90)
			(layer "B.Fab")
			(effects
				(font
					(size 0.7 0.7)
					(thickness 0.15)
				)
				(justify right top mirror)
			)
		)
		(fp_text user "License: Apache-2.0"
			(at -1.299 -4.924 90)
			(layer "B.Fab")
			(effects
				(font
					(size 0.7 0.7)
					(thickness 0.15)
				)
				(justify right top mirror)
			)
		)
		(fp_text user "${REFERENCE}"
			(at -1.299 -7.323 90)
			(layer "B.Fab")
			(effects
				(font
					(size 0.7 0.7)
					(thickness 0.15)
				)
				(justify right top mirror)
			)
		)
		(pad "1" smd roundrect
			(at -0.749 0.499 180)
			(size 0.3 0.6)
			(layers "B.Cu" "B.Mask" "B.Paste")
			(roundrect_rratio 0.25)
			(net 1 "GND")
			(pinfunction "S1")
			(pintype "passive")
		)
		(pad "2" smd roundrect
			(at -0.749 -0.001 180)
			(size 0.3 0.6)
			(layers "B.Cu" "B.Mask" "B.Paste")
			(roundrect_rratio 0.25)
			(net 1106 "/USB Hub/DP2_VCONN2")
			(pinfunction "G1")
			(pintype "input")
		)
		(pad "3" smd roundrect
			(at -0.749 -0.497 180)
			(size 0.3 0.6)
			(layers "B.Cu" "B.Mask" "B.Paste")
			(roundrect_rratio 0.25)
			(net 1236 "Net-(D58-A)")
			(pinfunction "D2")
			(pintype "passive")
		)
		(pad "4" smd roundrect
			(at 0.747 -0.497 180)
			(size 0.3 0.6)
			(layers "B.Cu" "B.Mask" "B.Paste")
			(roundrect_rratio 0.25)
			(net 5 "+5V")
			(pinfunction "S2")
			(pintype "passive")
		)
		(pad "5" smd roundrect
			(at 0.747 -0.001 180)
			(size 0.3 0.6)
			(layers "B.Cu" "B.Mask" "B.Paste")
			(roundrect_rratio 0.25)
			(net 1331 "Net-(Q26-D1)")
			(pinfunction "G2")
			(pintype "input")
		)
		(pad "6" smd roundrect
			(at 0.747 0.499 180)
			(size 0.3 0.6)
			(layers "B.Cu" "B.Mask" "B.Paste")
			(roundrect_rratio 0.25)
			(net 1331 "Net-(Q26-D1)")
			(pinfunction "D1")
			(pintype "passive")
		)
	)
	(footprint "antmicro-footprints:R_0402_1005Metric"
		(layer "B.Cu")
		(at 200.8 127.2 180)
		(descr "Resistor SMD 0402")
		(tags "resistor SMD 0402")
		(property "Reference" "R239"
			(at -3.8535 -0.41 0)
			(layer "B.SilkS")
			(effects
				(font
					(size 0.7 0.7)
					(thickness 0.15)
				)
				(justify left bottom mirror)
			)
		)
		(property "Value" "R_100k_0402"
			(at -1.011843 -1.772047 0)
			(layer "B.Fab")
			(effects
				(font
					(size 0.7 0.7)
					(thickness 0.15)
				)
				(justify left bottom mirror)
			)
		)
		(property "Datasheet" "https://www.bourns.com/docs/product-datasheets/cr.pdf"
			(at 0 0 0)
			(layer "B.Fab")
			(hide yes)
			(effects
				(font
					(size 1.27 1.27)
					(thickness 0.15)
				)
				(justify mirror)
			)
		)
		(property "Description" "SMD Chip Resistor, 100 kohm, ± 1%, 62.5 mW, 0402 [1005 Metric], Thick Film, General Purpose"
			(at 0 0 0)
			(layer "B.Fab")
			(hide yes)
			(effects
				(font
					(size 1.27 1.27)
					(thickness 0.15)
				)
				(justify mirror)
			)
		)
		(property "MPN" "CR0402-FX-1003GLF"
			(at 0 0 0)
			(unlocked yes)
			(layer "B.Fab")
			(hide yes)
			(effects
				(font
					(size 1 1)
					(thickness 0.15)
				)
				(justify mirror)
			)
		)
		(property "Manufacturer" "Bourns"
			(at 0 0 0)
			(unlocked yes)
			(layer "B.Fab")
			(hide yes)
			(effects
				(font
					(size 1 1)
					(thickness 0.15)
				)
				(justify mirror)
			)
		)
		(property "License" "Apache-2.0"
			(at 0 0 0)
			(unlocked yes)
			(layer "B.Fab")
			(hide yes)
			(effects
				(font
					(size 1 1)
					(thickness 0.15)
				)
				(justify mirror)
			)
		)
		(property "Author" "Antmicro"
			(at 0 0 0)
			(unlocked yes)
			(layer "B.Fab")
			(hide yes)
			(effects
				(font
					(size 1 1)
					(thickness 0.15)
				)
				(justify mirror)
			)
		)
		(property "Val" "100k"
			(at 0 0 0)
			(unlocked yes)
			(layer "B.Fab")
			(hide yes)
			(effects
				(font
					(size 1 1)
					(thickness 0.15)
				)
				(justify mirror)
			)
		)
		(property "Tolerance" "1%"
			(at 0 0 0)
			(unlocked yes)
			(layer "B.Fab")
			(hide yes)
			(effects
				(font
					(size 1 1)
					(thickness 0.15)
				)
				(justify mirror)
			)
		)
		(property "Current" "1A"
			(at 0 0 0)
			(unlocked yes)
			(layer "B.Fab")
			(hide yes)
			(effects
				(font
					(size 1 1)
					(thickness 0.15)
				)
				(justify mirror)
			)
		)
		(sheetname "/USB Hub/")
		(sheetfile "usb_hub.kicad_sch")
		(attr smd)
		(fp_rect
			(start -0.925 0.47)
			(end 0.925 -0.47)
			(stroke
				(width 0.05)
				(type default)
			)
			(fill no)
			(layer "B.CrtYd")
		)
		(fp_rect
			(start -0.5 0.25)
			(end 0.5 -0.25)
			(stroke
				(width 0.15)
				(type solid)
			)
			(fill no)
			(layer "B.Fab")
		)
		(fp_text user "License: Apache-2.0"
			(at -0.95 -5.169 0)
			(layer "B.Fab")
			(effects
				(font
					(size 0.7 0.7)
					(thickness 0.15)
				)
				(justify left bottom mirror)
			)
		)
		(fp_text user "${REFERENCE}"
			(at -0.95 -3.168 0)
			(layer "B.Fab")
			(effects
				(font
					(size 0.7 0.7)
					(thickness 0.15)
				)
				(justify left bottom mirror)
			)
		)
		(fp_text user "Author: Antmicro"
			(at -0.95 -4.169 0)
			(layer "B.Fab")
			(effects
				(font
					(size 0.7 0.7)
					(thickness 0.15)
				)
				(justify left bottom mirror)
			)
		)
		(pad "1" smd roundrect
			(at -0.48 0 180)
			(size 0.59 0.64)
			(layers "B.Cu" "B.Mask" "B.Paste")
			(roundrect_rratio 0.25)
			(net 1 "GND")
			(pintype "passive")
		)
		(pad "2" smd roundrect
			(at 0.48 0 180)
			(size 0.59 0.64)
			(layers "B.Cu" "B.Mask" "B.Paste")
			(roundrect_rratio 0.25)
			(net 921 "/USB Hub/HUB_SPI_D2")
			(pintype "passive")
		)
	)
	(footprint "antmicro-footprints:C_0402_1005Metric"
		(layer "B.Cu")
		(at 178.36 82.5 180)
		(descr "Capacitor SMD 0402")
		(tags "capacitor SMD 0402")
		(property "Reference" "C240"
			(at -0.07 -1.32 0)
			(layer "B.SilkS")
			(effects
				(font
					(size 0.7 0.7)
					(thickness 0.15)
				)
				(justify left bottom mirror)
			)
		)
		(property "Value" "C_100n_0402"
			(at -1.022927 -2.155213 0)
			(layer "B.Fab")
			(effects
				(font
					(size 0.7 0.7)
					(thickness 0.15)
				)
				(justify left bottom mirror)
			)
		)
		(property "Datasheet" "https://www.murata.com/products/productdetail?partno=GRM155R61H104KE14%23"
			(at 0 0 0)
			(layer "B.Fab")
			(hide yes)
			(effects
				(font
					(size 1.27 1.27)
					(thickness 0.15)
				)
				(justify mirror)
			)
		)
		(property "Description" "SMD Multilayer Ceramic Capacitor, 0.1 µF, 50 V, 0402 [1005 Metric], ± 10%, X5R, GRM Series"
			(at 0 0 0)
			(layer "B.Fab")
			(hide yes)
			(effects
				(font
					(size 1.27 1.27)
					(thickness 0.15)
				)
				(justify mirror)
			)
		)
		(property "MPN" "GRM155R61H104KE14D"
			(at 0 0 0)
			(unlocked yes)
			(layer "B.Fab")
			(hide yes)
			(effects
				(font
					(size 1 1)
					(thickness 0.15)
				)
				(justify mirror)
			)
		)
		(property "Manufacturer" "Murata"
			(at 0 0 0)
			(unlocked yes)
			(layer "B.Fab")
			(hide yes)
			(effects
				(font
					(size 1 1)
					(thickness 0.15)
				)
				(justify mirror)
			)
		)
		(property "License" "Apache-2.0"
			(at 0 0 0)
			(unlocked yes)
			(layer "B.Fab")
			(hide yes)
			(effects
				(font
					(size 1 1)
					(thickness 0.15)
				)
				(justify mirror)
			)
		)
		(property "Author" "Antmicro"
			(at 0 0 0)
			(unlocked yes)
			(layer "B.Fab")
			(hide yes)
			(effects
				(font
					(size 1 1)
					(thickness 0.15)
				)
				(justify mirror)
			)
		)
		(property "Val" "100n"
			(at 0 0 0)
			(unlocked yes)
			(layer "B.Fab")
			(hide yes)
			(effects
				(font
					(size 1 1)
					(thickness 0.15)
				)
				(justify mirror)
			)
		)
		(property "Voltage" "50V"
			(at 0 0 0)
			(unlocked yes)
			(layer "B.Fab")
			(hide yes)
			(effects
				(font
					(size 1 1)
					(thickness 0.15)
				)
				(justify mirror)
			)
		)
		(property "Dielectric" "X5R"
			(at 0 0 0)
			(unlocked yes)
			(layer "B.Fab")
			(hide yes)
			(effects
				(font
					(size 1 1)
					(thickness 0.15)
				)
				(justify mirror)
			)
		)
		(sheetname "/Power/")
		(sheetfile "power.kicad_sch")
		(attr smd exclude_from_pos_files exclude_from_bom dnp)
		(fp_rect
			(start -0.925 0.47)
			(end 0.925 -0.47)
			(stroke
				(width 0.05)
				(type default)
			)
			(fill no)
			(layer "B.CrtYd")
		)
		(fp_line
			(start 0.504 0.25)
			(end 0.504 -0.248)
			(stroke
				(width 0.15)
				(type solid)
			)
			(layer "B.Fab")
		)
		(fp_line
			(start 0.504 -0.248)
			(end -0.494 -0.248)
			(stroke
				(width 0.15)
				(type solid)
			)
			(layer "B.Fab")
		)
		(fp_line
			(start -0.494 0.25)
			(end 0.504 0.25)
			(stroke
				(width 0.15)
				(type solid)
			)
			(layer "B.Fab")
		)
		(fp_line
			(start -0.494 -0.248)
			(end -0.494 0.25)
			(stroke
				(width 0.15)
				(type solid)
			)
			(layer "B.Fab")
		)
		(fp_text user "License: Apache-2.0"
			(at -0.939 -5.799 0)
			(layer "B.Fab")
			(effects
				(font
					(size 0.7 0.7)
					(thickness 0.15)
				)
				(justify left bottom mirror)
			)
		)
		(fp_text user "Author: Antmicro"
			(at -0.939 -3.399 0)
			(layer "B.Fab")
			(effects
				(font
					(size 0.7 0.7)
					(thickness 0.15)
				)
				(justify left bottom mirror)
			)
		)
		(fp_text user "${REFERENCE}"
			(at -0.939 -4.599 0)
			(layer "B.Fab")
			(effects
				(font
					(size 0.7 0.7)
					(thickness 0.15)
				)
				(justify left bottom mirror)
			)
		)
		(pad "1" smd roundrect
			(at -0.48 0 180)
			(size 0.59 0.64)
			(layers "B.Cu" "B.Mask" "B.Paste")
			(roundrect_rratio 0.25)
			(net 1 "GND")
			(pintype "passive")
		)
		(pad "2" smd roundrect
			(at 0.48 0 180)
			(size 0.59 0.64)
			(layers "B.Cu" "B.Mask" "B.Paste")
			(roundrect_rratio 0.25)
			(net 525 "/Power/USBPD2_HV")
			(pintype "passive")
		)
	)
)
